(kicad_pcb
	(version 20260206)
	(generator "pcbnew")
	(generator_version "10.0")
	(general
		(thickness 1.6)
		(legacy_teardrops no)
	)
	(paper "A4")
	(title_block
		(title "12092022_DA0F0TFB6D0_F0T_FAN_BOARD_MP5048_D_brd_v02_OCP.brd")
		(comment 1 "Grand Teton / footprints 516-521 of 924")
	)
	(layers
		(0 "F.Cu" signal "TOP")
		(4 "In1.Cu" signal "GND")
		(6 "In2.Cu" signal "IN1")
		(8 "In3.Cu" signal "IN2")
		(10 "In4.Cu" signal "GND1")
		(2 "B.Cu" signal "BOTTOM")
		(9 "F.Adhes" user "F.Adhesive")
		(11 "B.Adhes" user "B.Adhesive")
		(13 "F.Paste" user "Package Geometry/Pastemask Top")
		(15 "B.Paste" user "Package Geometry/Pastemask Bottom")
		(5 "F.SilkS" user "Ref Des/Silkscreen Top")
		(7 "B.SilkS" user "Ref Des/Silkscreen Bottom")
		(1 "F.Mask" user "Board Geometry/Soldermask Top")
		(3 "B.Mask" user "Board Geometry/Soldermask Bottom")
		(17 "Dwgs.User" user "User.Drawings")
		(19 "Cmts.User" user "User.Comments")
		(21 "Eco1.User" user "User.Eco1")
		(23 "Eco2.User" user "User.Eco2")
		(25 "Edge.Cuts" user "Board Geometry/Outline")
		(27 "Margin" user)
		(31 "F.CrtYd" user "Package Geometry/Place Bound Top")
		(29 "B.CrtYd" user "Package Geometry/Place Bound Bottom")
		(35 "F.Fab" user "Ref Des/Assembly Top")
		(33 "B.Fab" user "Ref Des/Assembly Bottom")
	)
	(footprint ""
		(layer "F.Cu")
		(at 37.846 -131.318 180)
		(property "Reference" "R5602"
			(at 0 0 180)
			(layer "F.SilkS")
			(hide yes)
			(effects
				(font
					(size 1.27 1.27)
				)
			)
		)
		(property "Value" ""
			(at 0 0 180)
			(layer "F.Fab")
			(effects
				(font
					(size 1.27 1.27)
				)
			)
		)
		(duplicate_pad_numbers_are_jumpers no)
		(fp_line
			(start 0.7874 0.4064)
			(end -0.7874 0.4064)
			(stroke
				(width 0.1524)
				(type default)
			)
			(layer "F.SilkS")
		)
		(fp_line
			(start 0.7874 -0.4064)
			(end 0.7874 0.4064)
			(stroke
				(width 0.1524)
				(type default)
			)
			(layer "F.SilkS")
		)
		(fp_line
			(start -0.7874 0.4064)
			(end -0.7874 -0.4064)
			(stroke
				(width 0.1524)
				(type default)
			)
			(layer "F.SilkS")
		)
		(fp_line
			(start -0.7874 -0.4064)
			(end 0.7874 -0.4064)
			(stroke
				(width 0.1524)
				(type default)
			)
			(layer "F.SilkS")
		)
		(fp_line
			(start 0.67945 0.3048)
			(end 0.120396 0.3048)
			(stroke
				(width 0.1)
				(type default)
			)
			(layer "F.Fab")
		)
		(fp_line
			(start 0.67945 -0.3048)
			(end 0.67945 0.3048)
			(stroke
				(width 0.1)
				(type default)
			)
			(layer "F.Fab")
		)
		(fp_line
			(start 0.12065 -0.2794)
			(end 0.12065 -0.3048)
			(stroke
				(width 0.1)
				(type default)
			)
			(layer "F.Fab")
		)
		(fp_line
			(start 0.12065 -0.3048)
			(end 0.67945 -0.3048)
			(stroke
				(width 0.1)
				(type default)
			)
			(layer "F.Fab")
		)
		(fp_line
			(start 0.120396 0.3048)
			(end 0.120396 0.2794)
			(stroke
				(width 0.1)
				(type default)
			)
			(layer "F.Fab")
		)
		(fp_line
			(start 0.120396 0.2794)
			(end -0.12065 0.2794)
			(stroke
				(width 0.1)
				(type default)
			)
			(layer "F.Fab")
		)
		(fp_line
			(start -0.12065 0.3048)
			(end -0.67945 0.3048)
			(stroke
				(width 0.1)
				(type default)
			)
			(layer "F.Fab")
		)
		(fp_line
			(start -0.12065 0.2794)
			(end -0.12065 0.3048)
			(stroke
				(width 0.1)
				(type default)
			)
			(layer "F.Fab")
		)
		(fp_line
			(start -0.12065 -0.2794)
			(end 0.12065 -0.2794)
			(stroke
				(width 0.1)
				(type default)
			)
			(layer "F.Fab")
		)
		(fp_line
			(start -0.12065 -0.305054)
			(end -0.12065 -0.2794)
			(stroke
				(width 0.1)
				(type default)
			)
			(layer "F.Fab")
		)
		(fp_line
			(start -0.67945 0.3048)
			(end -0.67945 -0.305054)
			(stroke
				(width 0.1)
				(type default)
			)
			(layer "F.Fab")
		)
		(fp_line
			(start -0.67945 -0.305054)
			(end -0.12065 -0.305054)
			(stroke
				(width 0.1)
				(type default)
			)
			(layer "F.Fab")
		)
		(pad "1" smd rect
			(at -0.40005 0)
			(size 0.4572 0.508)
			(layers "F.Cu" "F.Mask" "F.Paste")
			(net "FAN_1_TACH_OL")
		)
		(pad "2" smd rect
			(at 0.40005 0)
			(size 0.4572 0.508)
			(layers "F.Cu" "F.Mask" "F.Paste")
			(net "FAN_1_TACH_OL_R1")
		)
	)
	(footprint ""
		(layer "F.Cu")
		(at 3.81 -132.08)
		(property "Reference" "C2095"
			(at 0 0 0)
			(layer "F.SilkS")
			(hide yes)
			(effects
				(font
					(size 1.27 1.27)
				)
			)
		)
		(property "Value" ""
			(at 0 0 0)
			(layer "F.Fab")
			(effects
				(font
					(size 1.27 1.27)
				)
			)
		)
		(duplicate_pad_numbers_are_jumpers no)
		(fp_line
			(start -0.7874 -0.4064)
			(end 0.7874 -0.4064)
			(stroke
				(width 0.1524)
				(type default)
			)
			(layer "F.SilkS")
		)
		(fp_line
			(start -0.7874 0.4064)
			(end -0.7874 -0.4064)
			(stroke
				(width 0.1524)
				(type default)
			)
			(layer "F.SilkS")
		)
		(fp_line
			(start 0.7874 -0.4064)
			(end 0.7874 0.4064)
			(stroke
				(width 0.1524)
				(type default)
			)
			(layer "F.SilkS")
		)
		(fp_line
			(start 0.7874 0.4064)
			(end -0.7874 0.4064)
			(stroke
				(width 0.1524)
				(type default)
			)
			(layer "F.SilkS")
		)
		(fp_line
			(start -0.67945 -0.305054)
			(end -0.12065 -0.305054)
			(stroke
				(width 0.1)
				(type default)
			)
			(layer "F.Fab")
		)
		(fp_line
			(start -0.67945 0.3048)
			(end -0.67945 -0.305054)
			(stroke
				(width 0.1)
				(type default)
			)
			(layer "F.Fab")
		)
		(fp_line
			(start -0.12065 -0.305054)
			(end -0.12065 -0.2794)
			(stroke
				(width 0.1)
				(type default)
			)
			(layer "F.Fab")
		)
		(fp_line
			(start -0.12065 -0.2794)
			(end 0.12065 -0.2794)
			(stroke
				(width 0.1)
				(type default)
			)
			(layer "F.Fab")
		)
		(fp_line
			(start -0.12065 0.2794)
			(end -0.12065 0.3048)
			(stroke
				(width 0.1)
				(type default)
			)
			(layer "F.Fab")
		)
		(fp_line
			(start -0.12065 0.3048)
			(end -0.67945 0.3048)
			(stroke
				(width 0.1)
				(type default)
			)
			(layer "F.Fab")
		)
		(fp_line
			(start 0.120396 0.2794)
			(end -0.12065 0.2794)
			(stroke
				(width 0.1)
				(type default)
			)
			(layer "F.Fab")
		)
		(fp_line
			(start 0.120396 0.3048)
			(end 0.120396 0.2794)
			(stroke
				(width 0.1)
				(type default)
			)
			(layer "F.Fab")
		)
		(fp_line
			(start 0.12065 -0.3048)
			(end 0.67945 -0.3048)
			(stroke
				(width 0.1)
				(type default)
			)
			(layer "F.Fab")
		)
		(fp_line
			(start 0.12065 -0.2794)
			(end 0.12065 -0.3048)
			(stroke
				(width 0.1)
				(type default)
			)
			(layer "F.Fab")
		)
		(fp_line
			(start 0.67945 -0.3048)
			(end 0.67945 0.3048)
			(stroke
				(width 0.1)
				(type default)
			)
			(layer "F.Fab")
		)
		(fp_line
			(start 0.67945 0.3048)
			(end 0.120396 0.3048)
			(stroke
				(width 0.1)
				(type default)
			)
			(layer "F.Fab")
		)
		(pad "1" smd circle
			(at -0.40005 0)
			(size 0 0)
			(layers "F.Cu" "F.Mask" "F.Paste")
			(net "GND")
		)
		(pad "2" smd circle
			(at 0.40005 0)
			(size 0 0)
			(layers "F.Cu" "F.Mask" "F.Paste")
			(net "P3V3_AUX")
		)
	)
	(footprint ""
		(layer "F.Cu")
		(at 25.019 -162.941 90)
		(property "Reference" "R5272"
			(at 0 0 90)
			(layer "F.SilkS")
			(hide yes)
			(effects
				(font
					(size 1.27 1.27)
				)
			)
		)
		(property "Value" ""
			(at 0 0 90)
			(layer "F.Fab")
			(effects
				(font
					(size 1.27 1.27)
				)
			)
		)
		(duplicate_pad_numbers_are_jumpers no)
		(fp_line
			(start 0.7874 -0.4064)
			(end 0.7874 0.4064)
			(stroke
				(width 0.1524)
				(type default)
			)
			(layer "F.SilkS")
		)
		(fp_line
			(start -0.7874 -0.4064)
			(end 0.7874 -0.4064)
			(stroke
				(width 0.1524)
				(type default)
			)
			(layer "F.SilkS")
		)
		(fp_line
			(start 0.7874 0.4064)
			(end -0.7874 0.4064)
			(stroke
				(width 0.1524)
				(type default)
			)
			(layer "F.SilkS")
		)
		(fp_line
			(start -0.7874 0.4064)
			(end -0.7874 -0.4064)
			(stroke
				(width 0.1524)
				(type default)
			)
			(layer "F.SilkS")
		)
		(fp_line
			(start -0.12065 -0.305054)
			(end -0.12065 -0.2794)
			(stroke
				(width 0.1)
				(type default)
			)
			(layer "F.Fab")
		)
		(fp_line
			(start -0.67945 -0.305054)
			(end -0.12065 -0.305054)
			(stroke
				(width 0.1)
				(type default)
			)
			(layer "F.Fab")
		)
		(fp_line
			(start 0.67945 -0.3048)
			(end 0.67945 0.3048)
			(stroke
				(width 0.1)
				(type default)
			)
			(layer "F.Fab")
		)
		(fp_line
			(start 0.12065 -0.3048)
			(end 0.67945 -0.3048)
			(stroke
				(width 0.1)
				(type default)
			)
			(layer "F.Fab")
		)
		(fp_line
			(start 0.12065 -0.2794)
			(end 0.12065 -0.3048)
			(stroke
				(width 0.1)
				(type default)
			)
			(layer "F.Fab")
		)
		(fp_line
			(start -0.12065 -0.2794)
			(end 0.12065 -0.2794)
			(stroke
				(width 0.1)
				(type default)
			)
			(layer "F.Fab")
		)
		(fp_line
			(start 0.120396 0.2794)
			(end -0.12065 0.2794)
			(stroke
				(width 0.1)
				(type default)
			)
			(layer "F.Fab")
		)
		(fp_line
			(start -0.12065 0.2794)
			(end -0.12065 0.3048)
			(stroke
				(width 0.1)
				(type default)
			)
			(layer "F.Fab")
		)
		(fp_line
			(start 0.67945 0.3048)
			(end 0.120396 0.3048)
			(stroke
				(width 0.1)
				(type default)
			)
			(layer "F.Fab")
		)
		(fp_line
			(start 0.120396 0.3048)
			(end 0.120396 0.2794)
			(stroke
				(width 0.1)
				(type default)
			)
			(layer "F.Fab")
		)
		(fp_line
			(start -0.12065 0.3048)
			(end -0.67945 0.3048)
			(stroke
				(width 0.1)
				(type default)
			)
			(layer "F.Fab")
		)
		(fp_line
			(start -0.67945 0.3048)
			(end -0.67945 -0.305054)
			(stroke
				(width 0.1)
				(type default)
			)
			(layer "F.Fab")
		)
		(pad "1" smd circle
			(at -0.40005 0 90)
			(size 0 0)
			(layers "F.Cu" "F.Mask" "F.Paste")
			(net "SMB_FAN6_R_SCL")
		)
		(pad "2" smd circle
			(at 0.40005 0 90)
			(size 0 0)
			(layers "F.Cu" "F.Mask" "F.Paste")
			(net "P3V3_AUX")
		)
	)
	(footprint ""
		(layer "F.Cu")
		(at 29.337 -289.56 -90)
		(property "Reference" "U402"
			(at -1.778 1.11633 90)
			(unlocked yes)
			(layer "F.SilkS")
			(effects
				(font
					(size 0.7874 0.5842)
					(thickness 0.1524)
				)
				(justify left)
			)
		)
		(property "Value" ""
			(at 0 0 270)
			(layer "F.Fab")
			(effects
				(font
					(size 1.27 1.27)
				)
			)
		)
		(duplicate_pad_numbers_are_jumpers no)
		(fp_line
			(start -1.33096 1.100074)
			(end -1.33096 -1.100074)
			(stroke
				(width 0.1524)
				(type default)
			)
			(layer "F.SilkS")
		)
		(fp_line
			(start 1.33096 1.100074)
			(end -1.33096 1.100074)
			(stroke
				(width 0.1524)
				(type default)
			)
			(layer "F.SilkS")
		)
		(fp_line
			(start 0 -0.649986)
			(end 0.381 -1.100074)
			(stroke
				(width 0.1524)
				(type default)
			)
			(layer "F.SilkS")
		)
		(fp_line
			(start -1.33096 -1.100074)
			(end -0.381 -1.100074)
			(stroke
				(width 0.1524)
				(type default)
			)
			(layer "F.SilkS")
		)
		(fp_line
			(start -0.381 -1.100074)
			(end 0 -0.649986)
			(stroke
				(width 0.1524)
				(type default)
			)
			(layer "F.SilkS")
		)
		(fp_line
			(start 0.381 -1.100074)
			(end 1.33096 -1.100074)
			(stroke
				(width 0.1524)
				(type default)
			)
			(layer "F.SilkS")
		)
		(fp_line
			(start 1.33096 -1.100074)
			(end 1.33096 1.100074)
			(stroke
				(width 0.1524)
				(type default)
			)
			(layer "F.SilkS")
		)
		(fp_poly
			(pts
				(xy -0.748538 -2.082292) (xy -1.256538 -2.082292) (xy -1.002538 -1.320292)
			)
			(stroke
				(width 0)
				(type default)
			)
			(fill yes)
			(layer "F.SilkS")
		)
		(fp_line
			(start -0.674878 1.100074)
			(end -0.674878 -1.100074)
			(stroke
				(width 0.1)
				(type default)
			)
			(layer "F.Fab")
		)
		(fp_line
			(start 0.674878 1.100074)
			(end -0.674878 1.100074)
			(stroke
				(width 0.1)
				(type default)
			)
			(layer "F.Fab")
		)
		(fp_line
			(start -0.674878 -1.100074)
			(end 0.674878 -1.100074)
			(stroke
				(width 0.1)
				(type default)
			)
			(layer "F.Fab")
		)
		(fp_line
			(start 0.674878 -1.100074)
			(end 0.674878 1.100074)
			(stroke
				(width 0.1)
				(type default)
			)
			(layer "F.Fab")
		)
		(fp_poly
			(pts
				(xy -2.209292 -0.902462) (xy -2.209292 -0.394462) (xy -1.447292 -0.648462)
			)
			(stroke
				(width 0)
				(type default)
			)
			(fill yes)
			(layer "F.Fab")
		)
		(pad "1" smd rect
			(at -0.94996 -0.649986)
			(size 0.4064 0.508)
			(layers "F.Cu" "F.Mask" "F.Paste")
			(net "NC_U402_P1")
		)
		(pad "2" smd rect
			(at -0.94996 0)
			(size 0.4064 0.508)
			(layers "F.Cu" "F.Mask" "F.Paste")
			(net "FAN_7_PWM")
		)
		(pad "3" smd rect
			(at -0.94996 0.649986)
			(size 0.4064 0.508)
			(layers "F.Cu" "F.Mask" "F.Paste")
			(net "GND")
		)
		(pad "4" smd rect
			(at 0.94996 0.649986)
			(size 0.4064 0.508)
			(layers "F.Cu" "F.Mask" "F.Paste")
			(net "FAN_7_PWM_BUF")
		)
		(pad "5" smd rect
			(at 0.94996 -0.649986)
			(size 0.4064 0.508)
			(layers "F.Cu" "F.Mask" "F.Paste")
			(net "P3V3_AUX")
		)
	)
	(footprint ""
		(layer "F.Cu")
		(at 26.162 -33.401 -90)
		(property "Reference" "R5657"
			(at 0 0 270)
			(layer "F.SilkS")
			(hide yes)
			(effects
				(font
					(size 1.27 1.27)
				)
			)
		)
		(property "Value" ""
			(at 0 0 270)
			(layer "F.Fab")
			(effects
				(font
					(size 1.27 1.27)
				)
			)
		)
		(duplicate_pad_numbers_are_jumpers no)
		(fp_line
			(start -0.7874 0.4064)
			(end -0.7874 -0.4064)
			(stroke
				(width 0.1524)
				(type default)
			)
			(layer "F.SilkS")
		)
		(fp_line
			(start 0.7874 0.4064)
			(end -0.7874 0.4064)
			(stroke
				(width 0.1524)
				(type default)
			)
			(layer "F.SilkS")
		)
		(fp_line
			(start -0.7874 -0.4064)
			(end 0.7874 -0.4064)
			(stroke
				(width 0.1524)
				(type default)
			)
			(layer "F.SilkS")
		)
		(fp_line
			(start 0.7874 -0.4064)
			(end 0.7874 0.4064)
			(stroke
				(width 0.1524)
				(type default)
			)
			(layer "F.SilkS")
		)
		(fp_line
			(start -0.67945 0.3048)
			(end -0.67945 -0.305054)
			(stroke
				(width 0.1)
				(type default)
			)
			(layer "F.Fab")
		)
		(fp_line
			(start -0.12065 0.3048)
			(end -0.67945 0.3048)
			(stroke
				(width 0.1)
				(type default)
			)
			(layer "F.Fab")
		)
		(fp_line
			(start 0.120396 0.3048)
			(end 0.120396 0.2794)
			(stroke
				(width 0.1)
				(type default)
			)
			(layer "F.Fab")
		)
		(fp_line
			(start 0.67945 0.3048)
			(end 0.120396 0.3048)
			(stroke
				(width 0.1)
				(type default)
			)
			(layer "F.Fab")
		)
		(fp_line
			(start -0.12065 0.2794)
			(end -0.12065 0.3048)
			(stroke
				(width 0.1)
				(type default)
			)
			(layer "F.Fab")
		)
		(fp_line
			(start 0.120396 0.2794)
			(end -0.12065 0.2794)
			(stroke
				(width 0.1)
				(type default)
			)
			(layer "F.Fab")
		)
		(fp_line
			(start -0.12065 -0.2794)
			(end 0.12065 -0.2794)
			(stroke
				(width 0.1)
				(type default)
			)
			(layer "F.Fab")
		)
		(fp_line
			(start 0.12065 -0.2794)
			(end 0.12065 -0.3048)
			(stroke
				(width 0.1)
				(type default)
			)
			(layer "F.Fab")
		)
		(fp_line
			(start 0.12065 -0.3048)
			(end 0.67945 -0.3048)
			(stroke
				(width 0.1)
				(type default)
			)
			(layer "F.Fab")
		)
		(fp_line
			(start 0.67945 -0.3048)
			(end 0.67945 0.3048)
			(stroke
				(width 0.1)
				(type default)
			)
			(layer "F.Fab")
		)
		(fp_line
			(start -0.67945 -0.305054)
			(end -0.12065 -0.305054)
			(stroke
				(width 0.1)
				(type default)
			)
			(layer "F.Fab")
		)
		(fp_line
			(start -0.12065 -0.305054)
			(end -0.12065 -0.2794)
			(stroke
				(width 0.1)
				(type default)
			)
			(layer "F.Fab")
		)
		(pad "1" smd circle
			(at -0.40005 0 270)
			(size 0 0)
			(layers "F.Cu" "F.Mask" "F.Paste")
			(net "FAN_3_PRESENT")
		)
		(pad "2" smd circle
			(at 0.40005 0 270)
			(size 0 0)
			(layers "F.Cu" "F.Mask" "F.Paste")
			(net "GND")
		)
	)
	(footprint ""
		(layer "F.Cu")
		(at 34.798 -20.574)
		(property "Reference" "R5532"
			(at 0 0 0)
			(layer "F.SilkS")
			(hide yes)
			(effects
				(font
					(size 1.27 1.27)
				)
			)
		)
		(property "Value" ""
			(at 0 0 0)
			(layer "F.Fab")
			(effects
				(font
					(size 1.27 1.27)
				)
			)
		)
		(duplicate_pad_numbers_are_jumpers no)
		(fp_line
			(start -0.7874 -0.4064)
			(end 0.7874 -0.4064)
			(stroke
				(width 0.1524)
				(type default)
			)
			(layer "F.SilkS")
		)
		(fp_line
			(start -0.7874 0.4064)
			(end -0.7874 -0.4064)
			(stroke
				(width 0.1524)
				(type default)
			)
			(layer "F.SilkS")
		)
		(fp_line
			(start 0.7874 -0.4064)
			(end 0.7874 0.4064)
			(stroke
				(width 0.1524)
				(type default)
			)
			(layer "F.SilkS")
		)
		(fp_line
			(start 0.7874 0.4064)
			(end -0.7874 0.4064)
			(stroke
				(width 0.1524)
				(type default)
			)
			(layer "F.SilkS")
		)
		(fp_line
			(start -0.67945 -0.305054)
			(end -0.12065 -0.305054)
			(stroke
				(width 0.1)
				(type default)
			)
			(layer "F.Fab")
		)
		(fp_line
			(start -0.67945 0.3048)
			(end -0.67945 -0.305054)
			(stroke
				(width 0.1)
				(type default)
			)
			(layer "F.Fab")
		)
		(fp_line
			(start -0.12065 -0.305054)
			(end -0.12065 -0.2794)
			(stroke
				(width 0.1)
				(type default)
			)
			(layer "F.Fab")
		)
		(fp_line
			(start -0.12065 -0.2794)
			(end 0.12065 -0.2794)
			(stroke
				(width 0.1)
				(type default)
			)
			(layer "F.Fab")
		)
		(fp_line
			(start -0.12065 0.2794)
			(end -0.12065 0.3048)
			(stroke
				(width 0.1)
				(type default)
			)
			(layer "F.Fab")
		)
		(fp_line
			(start -0.12065 0.3048)
			(end -0.67945 0.3048)
			(stroke
				(width 0.1)
				(type default)
			)
			(layer "F.Fab")
		)
		(fp_line
			(start 0.120396 0.2794)
			(end -0.12065 0.2794)
			(stroke
				(width 0.1)
				(type default)
			)
			(layer "F.Fab")
		)
		(fp_line
			(start 0.120396 0.3048)
			(end 0.120396 0.2794)
			(stroke
				(width 0.1)
				(type default)
			)
			(layer "F.Fab")
		)
		(fp_line
			(start 0.12065 -0.3048)
			(end 0.67945 -0.3048)
			(stroke
				(width 0.1)
				(type default)
			)
			(layer "F.Fab")
		)
		(fp_line
			(start 0.12065 -0.2794)
			(end 0.12065 -0.3048)
			(stroke
				(width 0.1)
				(type default)
			)
			(layer "F.Fab")
		)
		(fp_line
			(start 0.67945 -0.3048)
			(end 0.67945 0.3048)
			(stroke
				(width 0.1)
				(type default)
			)
			(layer "F.Fab")
		)
		(fp_line
			(start 0.67945 0.3048)
			(end 0.120396 0.3048)
			(stroke
				(width 0.1)
				(type default)
			)
			(layer "F.Fab")
		)
		(pad "1" smd rect
			(at -0.40005 0 180)
			(size 0.4572 0.508)
			(layers "F.Cu" "F.Mask" "F.Paste")
			(net "P12V_LED_FAN3")
		)
		(pad "2" smd rect
			(at 0.40005 0 180)
			(size 0.4572 0.508)
			(layers "F.Cu" "F.Mask" "F.Paste")
			(net "FAN_3_OK_LED_R_N")
		)
	)
)
